(kicad_pcb
	(version 20241229)
	(generator "pcbnew")
	(generator_version "9.0")
	(general
		(thickness 1.711)
		(legacy_teardrops no)
	)
	(paper "A4")
	(title_block
		(title "Antmicro Baseboard for Jetson AGX Thor")
		(date "2026-02-18")
		(rev "1.1.0")
		(company "Antmicro Ltd")
		(comment 1 "www.antmicro.com")
		(comment 9 "footprints 98-102 of 1170")
	)
	(layers
		(0 "F.Cu" signal)
		(4 "In1.Cu" signal)
		(6 "In2.Cu" signal)
		(8 "In3.Cu" signal)
		(10 "In4.Cu" jumper)
		(12 "In5.Cu" signal)
		(14 "In6.Cu" signal)
		(16 "In7.Cu" signal)
		(18 "In8.Cu" signal)
		(2 "B.Cu" signal)
		(9 "F.Adhes" user "F.Adhesive")
		(11 "B.Adhes" user "B.Adhesive")
		(13 "F.Paste" user)
		(15 "B.Paste" user)
		(5 "F.SilkS" user "F.Silkscreen")
		(7 "B.SilkS" user "B.Silkscreen")
		(1 "F.Mask" user)
		(3 "B.Mask" user)
		(17 "Dwgs.User" user "User.Drawings")
		(19 "Cmts.User" user "User.Comments")
		(21 "Eco1.User" user "User.Eco1")
		(23 "Eco2.User" user "User.Eco2")
		(25 "Edge.Cuts" user)
		(27 "Margin" user)
		(31 "F.CrtYd" user "F.Courtyard")
		(29 "B.CrtYd" user "B.Courtyard")
		(35 "F.Fab" user)
		(33 "B.Fab" user)
	)
	(footprint "antmicro-footprints:LED_0603_1608Metric_G"
		(layer "F.Cu")
		(at 175.25 55.32 -90)
		(descr "LED SMD 0603 Green")
		(tags "LED SMD 0603 Green")
		(property "Reference" "D61"
			(at -1.055 1.495 90)
			(layer "F.SilkS")
			(effects
				(font
					(size 0.7 0.7)
					(thickness 0.15)
				)
				(justify right top)
			)
		)
		(property "Value" "LED_G_0603_LTST-C190GKT"
			(at -0.001 1.599 90)
			(layer "F.Fab")
			(effects
				(font
					(size 0.7 0.7)
					(thickness 0.15)
				)
				(justify right top)
			)
		)
		(property "Datasheet" "https://media.digikey.com/pdf/Data%20Sheets/Lite-On%20PDFs/LTST-C190GKT.pdf"
			(at 0 0 90)
			(layer "F.Fab")
			(hide yes)
			(effects
				(font
					(size 1.27 1.27)
					(thickness 0.15)
				)
			)
		)
		(property "Description" "LED, Green, SMD, 0603, 20 mA, 2.1 V, 569 nm"
			(at 0 0 90)
			(layer "F.Fab")
			(hide yes)
			(effects
				(font
					(size 1.27 1.27)
					(thickness 0.15)
				)
			)
		)
		(property "MPN" "LTST-C190GKT"
			(at 0 0 270)
			(unlocked yes)
			(layer "F.Fab")
			(hide yes)
			(effects
				(font
					(size 1 1)
					(thickness 0.15)
				)
			)
		)
		(property "Manufacturer" "Lite-On"
			(at 0 0 270)
			(unlocked yes)
			(layer "F.Fab")
			(hide yes)
			(effects
				(font
					(size 1 1)
					(thickness 0.15)
				)
			)
		)
		(property "Author" "Antmicro"
			(at 0 0 270)
			(unlocked yes)
			(layer "F.Fab")
			(hide yes)
			(effects
				(font
					(size 1 1)
					(thickness 0.15)
				)
			)
		)
		(property "License" "Apache-2.0"
			(at 0 0 270)
			(unlocked yes)
			(layer "F.Fab")
			(hide yes)
			(effects
				(font
					(size 1 1)
					(thickness 0.15)
				)
			)
		)
		(property "Color" "Green"
			(at 0 0 270)
			(unlocked yes)
			(layer "F.Fab")
			(hide yes)
			(effects
				(font
					(size 1 1)
					(thickness 0.15)
				)
			)
		)
		(sheetname "/Power/")
		(sheetfile "power.kicad_sch")
		(attr smd)
		(fp_line
			(start 0.22 0.35)
			(end -0.22 0.35)
			(stroke
				(width 0.15)
				(type solid)
			)
			(layer "F.SilkS")
		)
		(fp_line
			(start -0.094672 0.201008)
			(end -0.094672 -0.198992)
			(stroke
				(width 0.1)
				(type solid)
			)
			(layer "F.SilkS")
		)
		(fp_line
			(start 0.105328 0.201008)
			(end -0.094672 0.001008)
			(stroke
				(width 0.1)
				(type solid)
			)
			(layer "F.SilkS")
		)
		(fp_line
			(start 0.105328 0.201008)
			(end 0.105328 -0.198992)
			(stroke
				(width 0.1)
				(type solid)
			)
			(layer "F.SilkS")
		)
		(fp_line
			(start -0.094672 0.001008)
			(end -0.24 0.001008)
			(stroke
				(width 0.1)
				(type solid)
			)
			(layer "F.SilkS")
		)
		(fp_line
			(start -0.094672 0.001008)
			(end 0.105328 -0.198992)
			(stroke
				(width 0.1)
				(type solid)
			)
			(layer "F.SilkS")
		)
		(fp_line
			(start 0.105328 0.001008)
			(end 0.24 0.001)
			(stroke
				(width 0.1)
				(type solid)
			)
			(layer "F.SilkS")
		)
		(fp_line
			(start -1.18 -0.319)
			(end -1.18 0.321)
			(stroke
				(width 0.15)
				(type solid)
			)
			(layer "F.SilkS")
		)
		(fp_line
			(start 0.22 -0.35)
			(end -0.22 -0.35)
			(stroke
				(width 0.15)
				(type solid)
			)
			(layer "F.SilkS")
		)
		(fp_rect
			(start 1.25 0.65)
			(end -1.25 -0.65)
			(stroke
				(width 0.05)
				(type solid)
			)
			(fill no)
			(layer "F.CrtYd")
		)
		(fp_line
			(start -0.199 0.2)
			(end -0.199 0.1)
			(stroke
				(width 0.15)
				(type solid)
			)
			(layer "F.Fab")
		)
		(fp_line
			(start 0.201 0.2)
			(end 0.201 0)
			(stroke
				(width 0.15)
				(type solid)
			)
			(layer "F.Fab")
		)
		(fp_line
			(start -0.199 0)
			(end -0.597 0)
			(stroke
				(width 0.15)
				(type solid)
			)
			(layer "F.Fab")
		)
		(fp_line
			(start -0.101 0)
			(end 0.201 0.2)
			(stroke
				(width 0.15)
				(type solid)
			)
			(layer "F.Fab")
		)
		(fp_line
			(start 0.201 0)
			(end 0.201 -0.202)
			(stroke
				(width 0.15)
				(type solid)
			)
			(layer "F.Fab")
		)
		(fp_line
			(start 0.599 0)
			(end 0.201 0)
			(stroke
				(width 0.15)
				(type solid)
			)
			(layer "F.Fab")
		)
		(fp_line
			(start -0.199 -0.202)
			(end -0.199 0.1)
			(stroke
				(width 0.15)
				(type solid)
			)
			(layer "F.Fab")
		)
		(fp_line
			(start 0.201 -0.202)
			(end -0.101 0)
			(stroke
				(width 0.15)
				(type solid)
			)
			(layer "F.Fab")
		)
		(fp_rect
			(start 0.848 0.4)
			(end -0.85 -0.402)
			(stroke
				(width 0.15)
				(type solid)
			)
			(fill no)
			(layer "F.Fab")
		)
		(fp_text user "Author: Antmicro"
			(at -1.4224 4.799 90)
			(layer "F.Fab")
			(effects
				(font
					(size 0.7 0.7)
					(thickness 0.15)
				)
				(justify right top)
			)
		)
		(fp_text user "License: Apache-2.0"
			(at -1.4224 3.599 90)
			(layer "F.Fab")
			(effects
				(font
					(size 0.7 0.7)
					(thickness 0.15)
				)
				(justify right top)
			)
		)
		(fp_text user "${REFERENCE}"
			(at -1.4224 5.999 90)
			(layer "F.Fab")
			(effects
				(font
					(size 0.7 0.7)
					(thickness 0.15)
				)
				(justify right top)
			)
		)
		(pad "1" smd roundrect
			(at -0.7 0 90)
			(size 0.8 1)
			(layers "F.Cu" "F.Mask" "F.Paste")
			(roundrect_rratio 0.2)
			(net 1 "GND")
			(pinfunction "C")
			(pintype "passive")
		)
		(pad "2" smd roundrect
			(at 0.7 0 90)
			(size 0.8 1)
			(layers "F.Cu" "F.Mask" "F.Paste")
			(roundrect_rratio 0.2)
			(net 1286 "Net-(D61-A)")
			(pinfunction "A")
			(pintype "passive")
		)
	)
	(footprint "antmicro-footprints:C_0805_2012Metric"
		(layer "F.Cu")
		(at 164.059468 73.31 -90)
		(descr "Capacitor SMD 0805")
		(tags "capacitor SMD 0805")
		(property "Reference" "C301"
			(at -4.81 -0.540532 90)
			(layer "F.SilkS")
			(effects
				(font
					(size 0.7 0.7)
					(thickness 0.15)
				)
				(justify right top)
			)
		)
		(property "Value" "C_22u_25V_0805"
			(at -2.055717 1.963152 90)
			(layer "F.Fab")
			(effects
				(font
					(size 0.7 0.7)
					(thickness 0.15)
				)
				(justify right top)
			)
		)
		(property "Datasheet" "https://product.samsungsem.com/mlcc/CL21A226MAYNNN.do"
			(at 0 0 90)
			(layer "F.Fab")
			(hide yes)
			(effects
				(font
					(size 1.27 1.27)
					(thickness 0.15)
				)
			)
		)
		(property "Description" "SMT Multilayer Ceramic Capacitor, 22uF, +/-20%, 25V, X5R, 0805 [2012 Metric]"
			(at 0 0 90)
			(layer "F.Fab")
			(hide yes)
			(effects
				(font
					(size 1.27 1.27)
					(thickness 0.15)
				)
			)
		)
		(property "MPN" "CL21A226MAYNNNE"
			(at 0 0 270)
			(unlocked yes)
			(layer "F.Fab")
			(hide yes)
			(effects
				(font
					(size 1 1)
					(thickness 0.15)
				)
			)
		)
		(property "Manufacturer" "Samsung Electro-Mechanics"
			(at 0 0 270)
			(unlocked yes)
			(layer "F.Fab")
			(hide yes)
			(effects
				(font
					(size 1 1)
					(thickness 0.15)
				)
			)
		)
		(property "License" "Apache-2.0"
			(at 0 0 270)
			(unlocked yes)
			(layer "F.Fab")
			(hide yes)
			(effects
				(font
					(size 1 1)
					(thickness 0.15)
				)
			)
		)
		(property "Author" "Antmicro"
			(at 0 0 270)
			(unlocked yes)
			(layer "F.Fab")
			(hide yes)
			(effects
				(font
					(size 1 1)
					(thickness 0.15)
				)
			)
		)
		(property "Val" "22u"
			(at 0 0 270)
			(unlocked yes)
			(layer "F.Fab")
			(hide yes)
			(effects
				(font
					(size 1 1)
					(thickness 0.15)
				)
			)
		)
		(property "Voltage" "25V"
			(at 0 0 270)
			(unlocked yes)
			(layer "F.Fab")
			(hide yes)
			(effects
				(font
					(size 1 1)
					(thickness 0.15)
				)
			)
		)
		(property "Dielectric" "X5R"
			(at 0 0 270)
			(unlocked yes)
			(layer "F.Fab")
			(hide yes)
			(effects
				(font
					(size 1 1)
					(thickness 0.15)
				)
			)
		)
		(property "Public" "False"
			(at 0 0 270)
			(unlocked yes)
			(layer "F.Fab")
			(hide yes)
			(effects
				(font
					(size 1 1)
					(thickness 0.15)
				)
			)
		)
		(component_classes
			(class "DCDC_20V")
		)
		(sheetname "/DCDC/")
		(sheetfile "dcdc.kicad_sch")
		(attr smd)
		(fp_line
			(start -0.3 0.7)
			(end 0.3 0.7)
			(stroke
				(width 0.15)
				(type solid)
			)
			(layer "F.SilkS")
		)
		(fp_line
			(start -0.3 -0.7)
			(end 0.3 -0.7)
			(stroke
				(width 0.15)
				(type solid)
			)
			(layer "F.SilkS")
		)
		(fp_rect
			(start 1.95 -0.9)
			(end -1.95 0.9)
			(stroke
				(width 0.05)
				(type default)
			)
			(fill no)
			(layer "F.CrtYd")
		)
		(fp_rect
			(start -0.95 -0.675)
			(end 0.95 0.675)
			(stroke
				(width 0.15)
				(type solid)
			)
			(fill no)
			(layer "F.Fab")
		)
		(fp_text user "License: Apache-2.0"
			(at -1.9 4.947 90)
			(layer "F.Fab")
			(effects
				(font
					(size 0.7 0.7)
					(thickness 0.15)
				)
				(justify right top)
			)
		)
		(fp_text user "Author: Antmicro"
			(at -1.9 5.947 90)
			(layer "F.Fab")
			(effects
				(font
					(size 0.7 0.7)
					(thickness 0.15)
				)
				(justify right top)
			)
		)
		(fp_text user "${REFERENCE}"
			(at -1.9 3.947 90)
			(layer "F.Fab")
			(effects
				(font
					(size 0.7 0.7)
					(thickness 0.15)
				)
				(justify right top)
			)
		)
		(pad "1" smd roundrect
			(at -1.1 0 270)
			(size 1.2 1.3)
			(layers "F.Cu" "F.Mask" "F.Paste")
			(roundrect_rratio 0.25)
			(net 1 "GND")
			(pintype "passive")
		)
		(pad "2" smd roundrect
			(at 1.1 0 270)
			(size 1.2 1.3)
			(layers "F.Cu" "F.Mask" "F.Paste")
			(roundrect_rratio 0.25)
			(net 1105 "/DCDC/20V_OUT")
			(pintype "passive")
		)
	)
	(footprint "antmicro-footprints:R_0402_1005Metric"
		(layer "F.Cu")
		(at 147.8 117.2)
		(descr "Resistor SMD 0402")
		(tags "resistor SMD 0402")
		(property "Reference" "R360"
			(at -3.7 0.5 0)
			(layer "F.SilkS")
			(effects
				(font
					(size 0.7 0.7)
					(thickness 0.15)
				)
				(justify left bottom)
			)
		)
		(property "Value" "R_2k2_0402"
			(at -1.011843 1.772047 0)
			(layer "F.Fab")
			(effects
				(font
					(size 0.7 0.7)
					(thickness 0.15)
				)
				(justify left bottom)
			)
		)
		(property "Datasheet" "https://www.bourns.com/docs/product-datasheets/cr.pdf"
			(at 0 0 0)
			(layer "F.Fab")
			(hide yes)
			(effects
				(font
					(size 1.27 1.27)
					(thickness 0.15)
				)
			)
		)
		(property "Description" "SMD Chip Resistor, 2.2 kohm, ± 1%, 62.5 mW, 0402 [1005 Metric], Thick Film, General Purpose"
			(at 0 0 0)
			(layer "F.Fab")
			(hide yes)
			(effects
				(font
					(size 1.27 1.27)
					(thickness 0.15)
				)
			)
		)
		(property "MPN" "CR0402-FX-2201GLF"
			(at 0 0 0)
			(unlocked yes)
			(layer "F.Fab")
			(hide yes)
			(effects
				(font
					(size 1 1)
					(thickness 0.15)
				)
			)
		)
		(property "Manufacturer" "Bourns"
			(at 0 0 0)
			(unlocked yes)
			(layer "F.Fab")
			(hide yes)
			(effects
				(font
					(size 1 1)
					(thickness 0.15)
				)
			)
		)
		(property "License" "Apache-2.0"
			(at 0 0 0)
			(unlocked yes)
			(layer "F.Fab")
			(hide yes)
			(effects
				(font
					(size 1 1)
					(thickness 0.15)
				)
			)
		)
		(property "Author" "Antmicro"
			(at 0 0 0)
			(unlocked yes)
			(layer "F.Fab")
			(hide yes)
			(effects
				(font
					(size 1 1)
					(thickness 0.15)
				)
			)
		)
		(property "Val" "2k2"
			(at 0 0 0)
			(unlocked yes)
			(layer "F.Fab")
			(hide yes)
			(effects
				(font
					(size 1 1)
					(thickness 0.15)
				)
			)
		)
		(property "Tolerance" "1%"
			(at 0 0 0)
			(unlocked yes)
			(layer "F.Fab")
			(hide yes)
			(effects
				(font
					(size 1 1)
					(thickness 0.15)
				)
			)
		)
		(sheetname "/SoM_IO/")
		(sheetfile "som_io.kicad_sch")
		(attr smd)
		(fp_rect
			(start -0.925 -0.47)
			(end 0.925 0.47)
			(stroke
				(width 0.05)
				(type default)
			)
			(fill no)
			(layer "F.CrtYd")
		)
		(fp_rect
			(start -0.5 -0.25)
			(end 0.5 0.25)
			(stroke
				(width 0.15)
				(type solid)
			)
			(fill no)
			(layer "F.Fab")
		)
		(fp_text user "${REFERENCE}"
			(at -0.95 3.168 0)
			(layer "F.Fab")
			(effects
				(font
					(size 0.7 0.7)
					(thickness 0.15)
				)
				(justify left bottom)
			)
		)
		(fp_text user "Author: Antmicro"
			(at -0.95 4.169 0)
			(layer "F.Fab")
			(effects
				(font
					(size 0.7 0.7)
					(thickness 0.15)
				)
				(justify left bottom)
			)
		)
		(fp_text user "License: Apache-2.0"
			(at -0.95 5.169 0)
			(layer "F.Fab")
			(effects
				(font
					(size 0.7 0.7)
					(thickness 0.15)
				)
				(justify left bottom)
			)
		)
		(pad "1" smd roundrect
			(at -0.48 0)
			(size 0.59 0.64)
			(layers "F.Cu" "F.Mask" "F.Paste")
			(roundrect_rratio 0.25)
			(net 2 "+3V3")
			(pintype "passive")
		)
		(pad "2" smd roundrect
			(at 0.48 0)
			(size 0.59 0.64)
			(layers "F.Cu" "F.Mask" "F.Paste")
			(roundrect_rratio 0.25)
			(net 1000 "/SFP/I2C_{SFP}.SCL")
			(pintype "passive")
		)
	)
	(footprint "antmicro-footprints:TP_SMD_0.75mm"
		(layer "F.Cu")
		(at 200.2 73.45 -90)
		(property "Reference" "TP12"
			(at -3.35 0.2 90)
			(layer "F.SilkS")
			(effects
				(font
					(size 0.7 0.7)
					(thickness 0.15)
				)
				(justify right top)
			)
		)
		(property "Value" "TP_0.75mm_SMD"
			(at 0 1.2 90)
			(layer "F.Fab")
			(effects
				(font
					(size 0.7 0.7)
					(thickness 0.15)
				)
				(justify right top)
			)
		)
		(property "Description" "SMT test point"
			(at 0 0 90)
			(layer "F.Fab")
			(hide yes)
			(effects
				(font
					(size 1.27 1.27)
					(thickness 0.15)
				)
			)
		)
		(property "MPN" ""
			(at 0 0 270)
			(unlocked yes)
			(layer "F.Fab")
			(hide yes)
			(effects
				(font
					(size 1 1)
					(thickness 0.15)
				)
			)
		)
		(property "Manufacturer" ""
			(at 0 0 270)
			(unlocked yes)
			(layer "F.Fab")
			(hide yes)
			(effects
				(font
					(size 1 1)
					(thickness 0.15)
				)
			)
		)
		(property "Author" "Antmicro"
			(at 0 0 270)
			(unlocked yes)
			(layer "F.Fab")
			(hide yes)
			(effects
				(font
					(size 1 1)
					(thickness 0.15)
				)
			)
		)
		(property "License" "Apache-2.0"
			(at 0 0 270)
			(unlocked yes)
			(layer "F.Fab")
			(hide yes)
			(effects
				(font
					(size 1 1)
					(thickness 0.15)
				)
			)
		)
		(sheetname "/USB Debug, PD/")
		(sheetfile "usb_debug_pd.kicad_sch")
		(attr exclude_from_pos_files exclude_from_bom)
		(fp_circle
			(center 0 0)
			(end 0.475 0)
			(stroke
				(width 0.05)
				(type default)
			)
			(fill no)
			(layer "F.CrtYd")
		)
		(fp_text user "License: Apache-2.0"
			(at -0.4 5.101 90)
			(layer "F.Fab")
			(effects
				(font
					(size 0.7 0.7)
					(thickness 0.15)
				)
				(justify right top)
			)
		)
		(fp_text user "${REFERENCE}"
			(at -0.4 2.7 90)
			(layer "F.Fab")
			(effects
				(font
					(size 0.7 0.7)
					(thickness 0.15)
				)
				(justify right top)
			)
		)
		(fp_text user "Author: Antmicro"
			(at -0.4 3.901 90)
			(layer "F.Fab")
			(effects
				(font
					(size 0.7 0.7)
					(thickness 0.15)
				)
				(justify right top)
			)
		)
		(pad "1" smd circle
			(at 0 0 270)
			(size 0.75 0.75)
			(layers "F.Cu" "F.Mask")
			(net 1041 "/USB Debug, PD/~{PDC_I2C3_IRQ}")
			(pinfunction "1")
			(pintype "passive")
		)
	)
	(footprint "antmicro-footprints:C_0402_1005Metric"
		(layer "F.Cu")
		(at 133.325 54.875 180)
		(descr "Capacitor SMD 0402")
		(tags "capacitor SMD 0402")
		(property "Reference" "C6"
			(at -11.835 -0.115 0)
			(layer "F.SilkS")
			(effects
				(font
					(size 0.7 0.7)
					(thickness 0.15)
				)
				(justify right top)
			)
		)
		(property "Value" "C_100n_0402"
			(at -1.022927 2.155213 0)
			(layer "F.Fab")
			(effects
				(font
					(size 0.7 0.7)
					(thickness 0.15)
				)
				(justify right top)
			)
		)
		(property "Datasheet" "https://www.murata.com/products/productdetail?partno=GRM155R61H104KE14%23"
			(at 0 0 0)
			(layer "F.Fab")
			(hide yes)
			(effects
				(font
					(size 1.27 1.27)
					(thickness 0.15)
				)
			)
		)
		(property "Description" "SMD Multilayer Ceramic Capacitor, 0.1 µF, 50 V, 0402 [1005 Metric], ± 10%, X5R, GRM Series"
			(at 0 0 0)
			(layer "F.Fab")
			(hide yes)
			(effects
				(font
					(size 1.27 1.27)
					(thickness 0.15)
				)
			)
		)
		(property "MPN" "GRM155R61H104KE14D"
			(at 0 0 180)
			(unlocked yes)
			(layer "F.Fab")
			(hide yes)
			(effects
				(font
					(size 1 1)
					(thickness 0.15)
				)
			)
		)
		(property "Manufacturer" "Murata"
			(at 0 0 180)
			(unlocked yes)
			(layer "F.Fab")
			(hide yes)
			(effects
				(font
					(size 1 1)
					(thickness 0.15)
				)
			)
		)
		(property "License" "Apache-2.0"
			(at 0 0 180)
			(unlocked yes)
			(layer "F.Fab")
			(hide yes)
			(effects
				(font
					(size 1 1)
					(thickness 0.15)
				)
			)
		)
		(property "Author" "Antmicro"
			(at 0 0 180)
			(unlocked yes)
			(layer "F.Fab")
			(hide yes)
			(effects
				(font
					(size 1 1)
					(thickness 0.15)
				)
			)
		)
		(property "Val" "100n"
			(at 0 0 180)
			(unlocked yes)
			(layer "F.Fab")
			(hide yes)
			(effects
				(font
					(size 1 1)
					(thickness 0.15)
				)
			)
		)
		(property "Voltage" "50V"
			(at 0 0 180)
			(unlocked yes)
			(layer "F.Fab")
			(hide yes)
			(effects
				(font
					(size 1 1)
					(thickness 0.15)
				)
			)
		)
		(property "Dielectric" "X5R"
			(at 0 0 180)
			(unlocked yes)
			(layer "F.Fab")
			(hide yes)
			(effects
				(font
					(size 1 1)
					(thickness 0.15)
				)
			)
		)
		(sheetname "/DCDC/")
		(sheetfile "dcdc.kicad_sch")
		(attr smd)
		(fp_rect
			(start -0.925 -0.47)
			(end 0.925 0.47)
			(stroke
				(width 0.05)
				(type default)
			)
			(fill no)
			(layer "F.CrtYd")
		)
		(fp_line
			(start 0.504 0.248)
			(end -0.494 0.248)
			(stroke
				(width 0.15)
				(type solid)
			)
			(layer "F.Fab")
		)
		(fp_line
			(start 0.504 -0.25)
			(end 0.504 0.248)
			(stroke
				(width 0.15)
				(type solid)
			)
			(layer "F.Fab")
		)
		(fp_line
			(start -0.494 0.248)
			(end -0.494 -0.25)
			(stroke
				(width 0.15)
				(type solid)
			)
			(layer "F.Fab")
		)
		(fp_line
			(start -0.494 -0.25)
			(end 0.504 -0.25)
			(stroke
				(width 0.15)
				(type solid)
			)
			(layer "F.Fab")
		)
		(fp_text user "Author: Antmicro"
			(at -0.939 3.399 0)
			(layer "F.Fab")
			(effects
				(font
					(size 0.7 0.7)
					(thickness 0.15)
				)
				(justify right top)
			)
		)
		(fp_text user "${REFERENCE}"
			(at -0.939 4.599 0)
			(layer "F.Fab")
			(effects
				(font
					(size 0.7 0.7)
					(thickness 0.15)
				)
				(justify right top)
			)
		)
		(fp_text user "License: Apache-2.0"
			(at -0.939 5.799 0)
			(layer "F.Fab")
			(effects
				(font
					(size 0.7 0.7)
					(thickness 0.15)
				)
				(justify right top)
			)
		)
		(pad "1" smd roundrect
			(at -0.48 0 180)
			(size 0.59 0.64)
			(layers "F.Cu" "F.Mask" "F.Paste")
			(roundrect_rratio 0.25)
			(net 1 "GND")
			(pintype "passive")
		)
		(pad "2" smd roundrect
			(at 0.48 0 180)
			(size 0.59 0.64)
			(layers "F.Cu" "F.Mask" "F.Paste")
			(roundrect_rratio 0.25)
			(net 1305 "/DCDC/5V_{AON}_EN")
			(pintype "passive")
		)
	)
)
